(kicad_pcb
	(version 20260206)
	(generator "pcbnew")
	(generator_version "10.0")
	(general
		(thickness 1.6)
		(legacy_teardrops no)
	)
	(paper "A4")
	(title_block
		(title "04192023_DAF0TMB3IC0_F0TG_MB_C_brd_V02_OCP.brd")
		(comment 1 "Grand Teton / footprints 4838-4844 of 8354")
	)
	(layers
		(0 "F.Cu" signal "TOP")
		(4 "In1.Cu" signal "GND")
		(6 "In2.Cu" signal "IN1")
		(8 "In3.Cu" signal "GND1")
		(10 "In4.Cu" signal "IN2")
		(12 "In5.Cu" signal "GND2")
		(14 "In6.Cu" signal "IN3")
		(16 "In7.Cu" signal "GND3")
		(18 "In8.Cu" signal "VCC")
		(20 "In9.Cu" signal "VCC1")
		(22 "In10.Cu" signal "GND4")
		(24 "In11.Cu" signal "IN4")
		(26 "In12.Cu" signal "GND5")
		(28 "In13.Cu" signal "IN5")
		(30 "In14.Cu" signal "GND6")
		(32 "In15.Cu" signal "IN6")
		(34 "In16.Cu" signal "GND7")
		(2 "B.Cu" signal "BOTTOM")
		(9 "F.Adhes" user "F.Adhesive")
		(11 "B.Adhes" user "B.Adhesive")
		(13 "F.Paste" user "Package Geometry/Pastemask Top")
		(15 "B.Paste" user "Package Geometry/Pastemask Bottom")
		(5 "F.SilkS" user "Ref Des/Silkscreen Top")
		(7 "B.SilkS" user "Ref Des/Silkscreen Bottom")
		(1 "F.Mask" user "Board Geometry/Soldermask Top")
		(3 "B.Mask" user "Board Geometry/Soldermask Bottom")
		(17 "Dwgs.User" user "User.Drawings")
		(19 "Cmts.User" user "User.Comments")
		(21 "Eco1.User" user "User.Eco1")
		(23 "Eco2.User" user "User.Eco2")
		(25 "Edge.Cuts" user "Board Geometry/Outline")
		(27 "Margin" user)
		(31 "F.CrtYd" user "Package Geometry/Place Bound Top")
		(29 "B.CrtYd" user "Package Geometry/Place Bound Bottom")
		(35 "F.Fab" user "Ref Des/Assembly Top")
		(33 "B.Fab" user "Ref Des/Assembly Bottom")
	)
	(footprint ""
		(layer "F.Cu")
		(at 345.131644 -381.41783 -90)
		(property "Reference" "C949"
			(at 0 0 270)
			(layer "F.SilkS")
			(hide yes)
			(effects
				(font
					(size 1.27 1.27)
				)
			)
		)
		(property "Value" ""
			(at 0 0 270)
			(layer "F.Fab")
			(effects
				(font
					(size 1.27 1.27)
				)
			)
		)
		(duplicate_pad_numbers_are_jumpers no)
		(fp_line
			(start -0.299974 0.150114)
			(end -0.299974 -0.150114)
			(stroke
				(width 0.1)
				(type default)
			)
			(layer "F.Fab")
		)
		(fp_line
			(start 0.299974 0.150114)
			(end -0.299974 0.150114)
			(stroke
				(width 0.1)
				(type default)
			)
			(layer "F.Fab")
		)
		(fp_line
			(start -0.299974 -0.150114)
			(end 0.299974 -0.150114)
			(stroke
				(width 0.1)
				(type default)
			)
			(layer "F.Fab")
		)
		(fp_line
			(start 0.299974 -0.150114)
			(end 0.299974 0.150114)
			(stroke
				(width 0.1)
				(type default)
			)
			(layer "F.Fab")
		)
		(pad "1" smd rect
			(at -0.2667 0 270)
			(size 0.3048 0.381)
			(layers "F.Cu" "F.Mask" "F.Paste")
			(net "P5E_CPU0_P1_TX_C_DP<8>")
		)
		(pad "2" smd rect
			(at 0.2667 0 270)
			(size 0.3048 0.381)
			(layers "F.Cu" "F.Mask" "F.Paste")
			(net "P5E_CPU0_P1_TX_DP<8>")
		)
	)
	(footprint ""
		(layer "F.Cu")
		(at 254.592836 -120.31345)
		(property "Reference" "R3726"
			(at 0 0 0)
			(layer "F.SilkS")
			(hide yes)
			(effects
				(font
					(size 1.27 1.27)
				)
			)
		)
		(property "Value" ""
			(at 0 0 0)
			(layer "F.Fab")
			(effects
				(font
					(size 1.27 1.27)
				)
			)
		)
		(duplicate_pad_numbers_are_jumpers no)
		(fp_line
			(start -0.7874 -0.4064)
			(end 0.7874 -0.4064)
			(stroke
				(width 0.1524)
				(type default)
			)
			(layer "F.SilkS")
		)
		(fp_line
			(start -0.7874 0.4064)
			(end -0.7874 -0.4064)
			(stroke
				(width 0.1524)
				(type default)
			)
			(layer "F.SilkS")
		)
		(fp_line
			(start 0.7874 -0.4064)
			(end 0.7874 0.4064)
			(stroke
				(width 0.1524)
				(type default)
			)
			(layer "F.SilkS")
		)
		(fp_line
			(start 0.7874 0.4064)
			(end -0.7874 0.4064)
			(stroke
				(width 0.1524)
				(type default)
			)
			(layer "F.SilkS")
		)
		(fp_line
			(start -0.67945 -0.305054)
			(end -0.12065 -0.305054)
			(stroke
				(width 0.1)
				(type default)
			)
			(layer "F.Fab")
		)
		(fp_line
			(start -0.67945 0.3048)
			(end -0.67945 -0.305054)
			(stroke
				(width 0.1)
				(type default)
			)
			(layer "F.Fab")
		)
		(fp_line
			(start -0.12065 -0.305054)
			(end -0.12065 -0.2794)
			(stroke
				(width 0.1)
				(type default)
			)
			(layer "F.Fab")
		)
		(fp_line
			(start -0.12065 -0.2794)
			(end 0.12065 -0.2794)
			(stroke
				(width 0.1)
				(type default)
			)
			(layer "F.Fab")
		)
		(fp_line
			(start -0.12065 0.2794)
			(end -0.12065 0.3048)
			(stroke
				(width 0.1)
				(type default)
			)
			(layer "F.Fab")
		)
		(fp_line
			(start -0.12065 0.3048)
			(end -0.67945 0.3048)
			(stroke
				(width 0.1)
				(type default)
			)
			(layer "F.Fab")
		)
		(fp_line
			(start 0.120396 0.2794)
			(end -0.12065 0.2794)
			(stroke
				(width 0.1)
				(type default)
			)
			(layer "F.Fab")
		)
		(fp_line
			(start 0.120396 0.3048)
			(end 0.120396 0.2794)
			(stroke
				(width 0.1)
				(type default)
			)
			(layer "F.Fab")
		)
		(fp_line
			(start 0.12065 -0.3048)
			(end 0.67945 -0.3048)
			(stroke
				(width 0.1)
				(type default)
			)
			(layer "F.Fab")
		)
		(fp_line
			(start 0.12065 -0.2794)
			(end 0.12065 -0.3048)
			(stroke
				(width 0.1)
				(type default)
			)
			(layer "F.Fab")
		)
		(fp_line
			(start 0.67945 -0.3048)
			(end 0.67945 0.3048)
			(stroke
				(width 0.1)
				(type default)
			)
			(layer "F.Fab")
		)
		(fp_line
			(start 0.67945 0.3048)
			(end 0.120396 0.3048)
			(stroke
				(width 0.1)
				(type default)
			)
			(layer "F.Fab")
		)
		(pad "1" smd circle
			(at -0.40005 0)
			(size 0 0)
			(layers "F.Cu" "F.Mask" "F.Paste")
			(net "P3V3_AUX")
		)
		(pad "2" smd circle
			(at 0.40005 0)
			(size 0 0)
			(layers "F.Cu" "F.Mask" "F.Paste")
			(net "SMB_LM75_0_3V3AUX_SDA")
		)
	)
	(footprint ""
		(layer "F.Cu")
		(at 369.455446 -30.084522 -90)
		(property "Reference" "R1425"
			(at 0 0 270)
			(layer "F.SilkS")
			(hide yes)
			(effects
				(font
					(size 1.27 1.27)
				)
			)
		)
		(property "Value" ""
			(at 0 0 270)
			(layer "F.Fab")
			(effects
				(font
					(size 1.27 1.27)
				)
			)
		)
		(duplicate_pad_numbers_are_jumpers no)
		(fp_line
			(start -0.7874 0.4064)
			(end -0.7874 -0.4064)
			(stroke
				(width 0.1524)
				(type default)
			)
			(layer "F.SilkS")
		)
		(fp_line
			(start 0.7874 0.4064)
			(end -0.7874 0.4064)
			(stroke
				(width 0.1524)
				(type default)
			)
			(layer "F.SilkS")
		)
		(fp_line
			(start -0.7874 -0.4064)
			(end 0.7874 -0.4064)
			(stroke
				(width 0.1524)
				(type default)
			)
			(layer "F.SilkS")
		)
		(fp_line
			(start 0.7874 -0.4064)
			(end 0.7874 0.4064)
			(stroke
				(width 0.1524)
				(type default)
			)
			(layer "F.SilkS")
		)
		(fp_line
			(start -0.67945 0.3048)
			(end -0.67945 -0.305054)
			(stroke
				(width 0.1)
				(type default)
			)
			(layer "F.Fab")
		)
		(fp_line
			(start -0.12065 0.3048)
			(end -0.67945 0.3048)
			(stroke
				(width 0.1)
				(type default)
			)
			(layer "F.Fab")
		)
		(fp_line
			(start 0.120396 0.3048)
			(end 0.120396 0.2794)
			(stroke
				(width 0.1)
				(type default)
			)
			(layer "F.Fab")
		)
		(fp_line
			(start 0.67945 0.3048)
			(end 0.120396 0.3048)
			(stroke
				(width 0.1)
				(type default)
			)
			(layer "F.Fab")
		)
		(fp_line
			(start -0.12065 0.2794)
			(end -0.12065 0.3048)
			(stroke
				(width 0.1)
				(type default)
			)
			(layer "F.Fab")
		)
		(fp_line
			(start 0.120396 0.2794)
			(end -0.12065 0.2794)
			(stroke
				(width 0.1)
				(type default)
			)
			(layer "F.Fab")
		)
		(fp_line
			(start -0.12065 -0.2794)
			(end 0.12065 -0.2794)
			(stroke
				(width 0.1)
				(type default)
			)
			(layer "F.Fab")
		)
		(fp_line
			(start 0.12065 -0.2794)
			(end 0.12065 -0.3048)
			(stroke
				(width 0.1)
				(type default)
			)
			(layer "F.Fab")
		)
		(fp_line
			(start 0.12065 -0.3048)
			(end 0.67945 -0.3048)
			(stroke
				(width 0.1)
				(type default)
			)
			(layer "F.Fab")
		)
		(fp_line
			(start 0.67945 -0.3048)
			(end 0.67945 0.3048)
			(stroke
				(width 0.1)
				(type default)
			)
			(layer "F.Fab")
		)
		(fp_line
			(start -0.67945 -0.305054)
			(end -0.12065 -0.305054)
			(stroke
				(width 0.1)
				(type default)
			)
			(layer "F.Fab")
		)
		(fp_line
			(start -0.12065 -0.305054)
			(end -0.12065 -0.2794)
			(stroke
				(width 0.1)
				(type default)
			)
			(layer "F.Fab")
		)
		(pad "1" smd circle
			(at -0.40005 0 270)
			(size 0 0)
			(layers "F.Cu" "F.Mask" "F.Paste")
			(net "UART_CPU0_SCM_LVC3_UART1_R_TX")
		)
		(pad "2" smd circle
			(at 0.40005 0 270)
			(size 0 0)
			(layers "F.Cu" "F.Mask" "F.Paste")
			(net "UART_CPU0_SCM_LVC3_UART1_TX")
		)
	)
	(footprint ""
		(layer "F.Cu")
		(at 417.623752 -159.310324)
		(property "Reference" "PC605_9"
			(at 0 0 0)
			(layer "F.SilkS")
			(hide yes)
			(effects
				(font
					(size 1.27 1.27)
				)
			)
		)
		(property "Value" ""
			(at 0 0 0)
			(layer "F.Fab")
			(effects
				(font
					(size 1.27 1.27)
				)
			)
		)
		(duplicate_pad_numbers_are_jumpers no)
		(fp_line
			(start -0.7874 -0.4064)
			(end 0.7874 -0.4064)
			(stroke
				(width 0.1524)
				(type default)
			)
			(layer "F.SilkS")
		)
		(fp_line
			(start -0.7874 0.4064)
			(end -0.7874 -0.4064)
			(stroke
				(width 0.1524)
				(type default)
			)
			(layer "F.SilkS")
		)
		(fp_line
			(start 0.7874 -0.4064)
			(end 0.7874 0.4064)
			(stroke
				(width 0.1524)
				(type default)
			)
			(layer "F.SilkS")
		)
		(fp_line
			(start 0.7874 0.4064)
			(end -0.7874 0.4064)
			(stroke
				(width 0.1524)
				(type default)
			)
			(layer "F.SilkS")
		)
		(fp_line
			(start -0.67945 -0.305054)
			(end -0.12065 -0.305054)
			(stroke
				(width 0.1)
				(type default)
			)
			(layer "F.Fab")
		)
		(fp_line
			(start -0.67945 0.3048)
			(end -0.67945 -0.305054)
			(stroke
				(width 0.1)
				(type default)
			)
			(layer "F.Fab")
		)
		(fp_line
			(start -0.12065 -0.305054)
			(end -0.12065 -0.2794)
			(stroke
				(width 0.1)
				(type default)
			)
			(layer "F.Fab")
		)
		(fp_line
			(start -0.12065 -0.2794)
			(end 0.12065 -0.2794)
			(stroke
				(width 0.1)
				(type default)
			)
			(layer "F.Fab")
		)
		(fp_line
			(start -0.12065 0.2794)
			(end -0.12065 0.3048)
			(stroke
				(width 0.1)
				(type default)
			)
			(layer "F.Fab")
		)
		(fp_line
			(start -0.12065 0.3048)
			(end -0.67945 0.3048)
			(stroke
				(width 0.1)
				(type default)
			)
			(layer "F.Fab")
		)
		(fp_line
			(start 0.120396 0.2794)
			(end -0.12065 0.2794)
			(stroke
				(width 0.1)
				(type default)
			)
			(layer "F.Fab")
		)
		(fp_line
			(start 0.120396 0.3048)
			(end 0.120396 0.2794)
			(stroke
				(width 0.1)
				(type default)
			)
			(layer "F.Fab")
		)
		(fp_line
			(start 0.12065 -0.3048)
			(end 0.67945 -0.3048)
			(stroke
				(width 0.1)
				(type default)
			)
			(layer "F.Fab")
		)
		(fp_line
			(start 0.12065 -0.2794)
			(end 0.12065 -0.3048)
			(stroke
				(width 0.1)
				(type default)
			)
			(layer "F.Fab")
		)
		(fp_line
			(start 0.67945 -0.3048)
			(end 0.67945 0.3048)
			(stroke
				(width 0.1)
				(type default)
			)
			(layer "F.Fab")
		)
		(fp_line
			(start 0.67945 0.3048)
			(end 0.120396 0.3048)
			(stroke
				(width 0.1)
				(type default)
			)
			(layer "F.Fab")
		)
		(pad "1" smd circle
			(at -0.40005 0)
			(size 0 0)
			(layers "F.Cu" "F.Mask" "F.Paste")
			(net "PVDDCR_CPU0_P0_VCCS")
		)
		(pad "2" smd circle
			(at 0.40005 0)
			(size 0 0)
			(layers "F.Cu" "F.Mask" "F.Paste")
			(net "GND")
		)
	)
	(footprint ""
		(layer "F.Cu")
		(at 427.30166 -351.20326 -90)
		(property "Reference" "PC209_1"
			(at 0 0 270)
			(layer "F.SilkS")
			(hide yes)
			(effects
				(font
					(size 1.27 1.27)
				)
			)
		)
		(property "Value" ""
			(at 0 0 270)
			(layer "F.Fab")
			(effects
				(font
					(size 1.27 1.27)
				)
			)
		)
		(duplicate_pad_numbers_are_jumpers no)
		(fp_line
			(start -0.7874 0.4064)
			(end -0.7874 -0.4064)
			(stroke
				(width 0.1524)
				(type default)
			)
			(layer "F.SilkS")
		)
		(fp_line
			(start 0.7874 0.4064)
			(end -0.7874 0.4064)
			(stroke
				(width 0.1524)
				(type default)
			)
			(layer "F.SilkS")
		)
		(fp_line
			(start -0.7874 -0.4064)
			(end 0.7874 -0.4064)
			(stroke
				(width 0.1524)
				(type default)
			)
			(layer "F.SilkS")
		)
		(fp_line
			(start 0.7874 -0.4064)
			(end 0.7874 0.4064)
			(stroke
				(width 0.1524)
				(type default)
			)
			(layer "F.SilkS")
		)
		(fp_line
			(start -0.67945 0.3048)
			(end -0.67945 -0.305054)
			(stroke
				(width 0.1)
				(type default)
			)
			(layer "F.Fab")
		)
		(fp_line
			(start -0.12065 0.3048)
			(end -0.67945 0.3048)
			(stroke
				(width 0.1)
				(type default)
			)
			(layer "F.Fab")
		)
		(fp_line
			(start 0.120396 0.3048)
			(end 0.120396 0.2794)
			(stroke
				(width 0.1)
				(type default)
			)
			(layer "F.Fab")
		)
		(fp_line
			(start 0.67945 0.3048)
			(end 0.120396 0.3048)
			(stroke
				(width 0.1)
				(type default)
			)
			(layer "F.Fab")
		)
		(fp_line
			(start -0.12065 0.2794)
			(end -0.12065 0.3048)
			(stroke
				(width 0.1)
				(type default)
			)
			(layer "F.Fab")
		)
		(fp_line
			(start 0.120396 0.2794)
			(end -0.12065 0.2794)
			(stroke
				(width 0.1)
				(type default)
			)
			(layer "F.Fab")
		)
		(fp_line
			(start -0.12065 -0.2794)
			(end 0.12065 -0.2794)
			(stroke
				(width 0.1)
				(type default)
			)
			(layer "F.Fab")
		)
		(fp_line
			(start 0.12065 -0.2794)
			(end 0.12065 -0.3048)
			(stroke
				(width 0.1)
				(type default)
			)
			(layer "F.Fab")
		)
		(fp_line
			(start 0.12065 -0.3048)
			(end 0.67945 -0.3048)
			(stroke
				(width 0.1)
				(type default)
			)
			(layer "F.Fab")
		)
		(fp_line
			(start 0.67945 -0.3048)
			(end 0.67945 0.3048)
			(stroke
				(width 0.1)
				(type default)
			)
			(layer "F.Fab")
		)
		(fp_line
			(start -0.67945 -0.305054)
			(end -0.12065 -0.305054)
			(stroke
				(width 0.1)
				(type default)
			)
			(layer "F.Fab")
		)
		(fp_line
			(start -0.12065 -0.305054)
			(end -0.12065 -0.2794)
			(stroke
				(width 0.1)
				(type default)
			)
			(layer "F.Fab")
		)
		(pad "1" smd circle
			(at -0.40005 0 270)
			(size 0 0)
			(layers "F.Cu" "F.Mask" "F.Paste")
			(net "SW_P12V_AUX_PVDD11_S3_P0_FLT")
		)
		(pad "2" smd circle
			(at 0.40005 0 270)
			(size 0 0)
			(layers "F.Cu" "F.Mask" "F.Paste")
			(net "GND")
		)
	)
	(footprint ""
		(layer "F.Cu")
		(at 280.019506 -346.714572 -90)
		(property "Reference" "PC174_IOP0_3"
			(at 0 0 270)
			(layer "F.SilkS")
			(hide yes)
			(effects
				(font
					(size 1.27 1.27)
				)
			)
		)
		(property "Value" ""
			(at 0 0 270)
			(layer "F.Fab")
			(effects
				(font
					(size 1.27 1.27)
				)
			)
		)
		(duplicate_pad_numbers_are_jumpers no)
		(fp_line
			(start -0.7874 0.4064)
			(end -0.7874 -0.4064)
			(stroke
				(width 0.1524)
				(type default)
			)
			(layer "F.SilkS")
		)
		(fp_line
			(start 0.7874 0.4064)
			(end -0.7874 0.4064)
			(stroke
				(width 0.1524)
				(type default)
			)
			(layer "F.SilkS")
		)
		(fp_line
			(start -0.7874 -0.4064)
			(end 0.7874 -0.4064)
			(stroke
				(width 0.1524)
				(type default)
			)
			(layer "F.SilkS")
		)
		(fp_line
			(start 0.7874 -0.4064)
			(end 0.7874 0.4064)
			(stroke
				(width 0.1524)
				(type default)
			)
			(layer "F.SilkS")
		)
		(fp_line
			(start -0.67945 0.3048)
			(end -0.67945 -0.305054)
			(stroke
				(width 0.1)
				(type default)
			)
			(layer "F.Fab")
		)
		(fp_line
			(start -0.12065 0.3048)
			(end -0.67945 0.3048)
			(stroke
				(width 0.1)
				(type default)
			)
			(layer "F.Fab")
		)
		(fp_line
			(start 0.120396 0.3048)
			(end 0.120396 0.2794)
			(stroke
				(width 0.1)
				(type default)
			)
			(layer "F.Fab")
		)
		(fp_line
			(start 0.67945 0.3048)
			(end 0.120396 0.3048)
			(stroke
				(width 0.1)
				(type default)
			)
			(layer "F.Fab")
		)
		(fp_line
			(start -0.12065 0.2794)
			(end -0.12065 0.3048)
			(stroke
				(width 0.1)
				(type default)
			)
			(layer "F.Fab")
		)
		(fp_line
			(start 0.120396 0.2794)
			(end -0.12065 0.2794)
			(stroke
				(width 0.1)
				(type default)
			)
			(layer "F.Fab")
		)
		(fp_line
			(start -0.12065 -0.2794)
			(end 0.12065 -0.2794)
			(stroke
				(width 0.1)
				(type default)
			)
			(layer "F.Fab")
		)
		(fp_line
			(start 0.12065 -0.2794)
			(end 0.12065 -0.3048)
			(stroke
				(width 0.1)
				(type default)
			)
			(layer "F.Fab")
		)
		(fp_line
			(start 0.12065 -0.3048)
			(end 0.67945 -0.3048)
			(stroke
				(width 0.1)
				(type default)
			)
			(layer "F.Fab")
		)
		(fp_line
			(start 0.67945 -0.3048)
			(end 0.67945 0.3048)
			(stroke
				(width 0.1)
				(type default)
			)
			(layer "F.Fab")
		)
		(fp_line
			(start -0.67945 -0.305054)
			(end -0.12065 -0.305054)
			(stroke
				(width 0.1)
				(type default)
			)
			(layer "F.Fab")
		)
		(fp_line
			(start -0.12065 -0.305054)
			(end -0.12065 -0.2794)
			(stroke
				(width 0.1)
				(type default)
			)
			(layer "F.Fab")
		)
		(pad "1" smd circle
			(at -0.40005 0 270)
			(size 0 0)
			(layers "F.Cu" "F.Mask" "F.Paste")
			(net "PVDDCR_CPU1_P0_PVCC")
		)
		(pad "2" smd circle
			(at 0.40005 0 270)
			(size 0 0)
			(layers "F.Cu" "F.Mask" "F.Paste")
			(net "GND")
		)
	)
	(footprint ""
		(layer "F.Cu")
		(at 466.8901 -51.289966)
		(property "Reference" "H6001"
			(at -2.5146 -4.17957 0)
			(unlocked yes)
			(layer "F.SilkS")
			(effects
				(font
					(size 0.7874 0.5842)
					(thickness 0.1524)
				)
				(justify left)
			)
		)
		(property "Value" ""
			(at 0 0 0)
			(layer "F.Fab")
			(effects
				(font
					(size 1.27 1.27)
				)
			)
		)
		(duplicate_pad_numbers_are_jumpers no)
		(pad "1" thru_hole circle
			(at 0 0)
			(size 6.1976 6.1976)
			(drill 3.7338)
			(layers "*.Cu" "*.Mask")
			(remove_unused_layers no)
			(net "GND")
			(clearance -0.9779)
			(padstack
				(mode front_inner_back)
				(layer "Inner"
					(shape circle)
					(size 5.5372 5.5372)
					(clearance -0.6477)
				)
				(layer "B.Cu"
					(shape circle)
					(size 6.1976 6.1976)
					(clearance -0.9779)
				)
			)
		)
	)
)
